#ISCELL
  logical_power bom_note *
  *
#ISCELL
  logical_power cad_note *
  *
#ISCELL
  pure_quanta quanta_title_block_c *
  *
#ISCELL
  logical_power universal_gnd *
  page83_i1
#CELL
  pure_quanta q_res *
  page83_i10
#ISCELL
  standard tap *
  page83_i100
#ISCELL
  standard tap *
  page83_i101
#ISCELL
  standard tap *
  page83_i102
#ISCELL
  standard tap *
  page83_i103
#ISCELL
  standard tap *
  page83_i104
#ISCELL
  standard tap *
  page83_i105
#ISCELL
  standard tap *
  page83_i106
#ISCELL
  standard tap *
  page83_i107
#ISCELL
  standard offpage *
  page83_i108
#ISCELL
  standard tap *
  page83_i109
#ISCELL
  standard tap *
  page83_i110
#ISCELL
  standard tap *
  page83_i111
#ISCELL
  standard tap *
  page83_i112
#ISCELL
  standard tap *
  page83_i113
#ISCELL
  standard tap *
  page83_i114
#ISCELL
  standard tap *
  page83_i115
#ISCELL
  standard tap *
  page83_i116
#ISCELL
  standard tap *
  page83_i117
#ISCELL
  standard tap *
  page83_i118
#ISCELL
  logical_power vcc_core *
  page83_i119
#ISCELL
  standard offpage *
  page83_i12
#CELL
  pure_quanta q_cap *
  page83_i120
#ISCELL
  logical_power universal_gnd *
  page83_i121
#CELL
  pure_quanta q_cap *
  page83_i122
#ISCELL
  logical_power vcc_core *
  page83_i123
#ISCELL
  standard offpage *
  page83_i124
#ISCELL
  standard tap *
  page83_i126
#ISCELL
  standard tap *
  page83_i127
#ISCELL
  standard tap *
  page83_i128
#ISCELL
  standard tap *
  page83_i129
#ISCELL
  logical_power vcc_core *
  page83_i13
#ISCELL
  standard tap *
  page83_i130
#ISCELL
  standard tap *
  page83_i131
#ISCELL
  standard tap *
  page83_i132
#ISCELL
  standard tap *
  page83_i133
#ISCELL
  standard tap *
  page83_i134
#ISCELL
  standard tap *
  page83_i135
#ISCELL
  standard tap *
  page83_i136
#ISCELL
  standard tap *
  page83_i137
#ISCELL
  standard tap *
  page83_i138
#ISCELL
  standard tap *
  page83_i139
#ISCELL
  standard offpage *
  page83_i14
#ISCELL
  standard tap *
  page83_i140
#ISCELL
  standard tap *
  page83_i141
#ISCELL
  standard tap *
  page83_i142
#ISCELL
  logical_power universal_gnd *
  page83_i143
#CELL
  pure_quanta q_cap *
  page83_i144
#ISCELL
  logical_power universal_gnd *
  page83_i145
#ISCELL
  standard tap *
  page83_i147
#ISCELL
  standard tap *
  page83_i148
#ISCELL
  standard tap *
  page83_i149
#ISCELL
  standard offpage *
  page83_i15
#ISCELL
  standard tap *
  page83_i150
#ISCELL
  standard tap *
  page83_i151
#ISCELL
  standard tap *
  page83_i152
#ISCELL
  standard tap *
  page83_i153
#ISCELL
  standard tap *
  page83_i154
#ISCELL
  standard tap *
  page83_i155
#ISCELL
  standard tap *
  page83_i156
#ISCELL
  standard tap *
  page83_i157
#ISCELL
  standard tap *
  page83_i158
#ISCELL
  standard tap *
  page83_i159
#ISCELL
  standard offpage *
  page83_i16
#ISCELL
  standard tap *
  page83_i160
#ISCELL
  standard tap *
  page83_i161
#ISCELL
  standard tap *
  page83_i162
#ISCELL
  standard tap *
  page83_i163
#ISCELL
  standard tap *
  page83_i164
#ISCELL
  standard offpage *
  page83_i165
#ISCELL
  standard offpage *
  page83_i166
#ISCELL
  standard offpage *
  page83_i167
#ISCELL
  standard tap *
  page83_i168
#ISCELL
  standard tap *
  page83_i169
#ISCELL
  standard offpage *
  page83_i17
#ISCELL
  standard tap *
  page83_i170
#ISCELL
  standard tap *
  page83_i171
#ISCELL
  standard tap *
  page83_i172
#ISCELL
  standard offpage *
  page83_i173
#ISCELL
  standard offpage *
  page83_i174
#ISCELL
  logical_power vcc_core *
  page83_i175
#ISCELL
  logical_power universal_gnd *
  page83_i176
#CELL
  pure_quanta sconn288_adr50017p087cc *
  page83_i177
#CELL
  pure_quanta sconn288_adr50017p087cc *
  page83_i179
#ISCELL
  standard offpage *
  page83_i18
#ISCELL
  standard offpage *
  page83_i180
#CELL
  pure_quanta sconn288_adr50017p087cc *
  page83_i181
#CELL
  pure_quanta q_res *
  page83_i182
#ISCELL
  standard offpage *
  page83_i183
#ISCELL
  standard offpage *
  page83_i19
#ISCELL
  standard offpage *
  page83_i2
#ISCELL
  standard offpage *
  page83_i20
#ISCELL
  standard offpage *
  page83_i21
#ISCELL
  standard offpage *
  page83_i22
#ISCELL
  standard offpage *
  page83_i23
#ISCELL
  standard tap *
  page83_i24
#ISCELL
  standard tap *
  page83_i25
#ISCELL
  standard tap *
  page83_i26
#ISCELL
  standard tap *
  page83_i27
#ISCELL
  standard tap *
  page83_i28
#ISCELL
  standard tap *
  page83_i29
#ISCELL
  standard offpage *
  page83_i3
#ISCELL
  standard tap *
  page83_i30
#ISCELL
  standard tap *
  page83_i31
#ISCELL
  standard tap *
  page83_i32
#ISCELL
  standard tap *
  page83_i33
#ISCELL
  standard tap *
  page83_i34
#ISCELL
  standard tap *
  page83_i35
#ISCELL
  standard tap *
  page83_i36
#ISCELL
  standard tap *
  page83_i37
#ISCELL
  standard tap *
  page83_i38
#ISCELL
  standard tap *
  page83_i39
#ISCELL
  standard offpage *
  page83_i4
#ISCELL
  standard tap *
  page83_i40
#ISCELL
  standard tap *
  page83_i41
#ISCELL
  standard tap *
  page83_i42
#ISCELL
  standard tap *
  page83_i43
#ISCELL
  standard tap *
  page83_i44
#ISCELL
  standard tap *
  page83_i45
#ISCELL
  standard tap *
  page83_i46
#ISCELL
  standard tap *
  page83_i47
#ISCELL
  standard tap *
  page83_i48
#ISCELL
  standard tap *
  page83_i49
#ISCELL
  standard tap *
  page83_i50
#ISCELL
  standard tap *
  page83_i51
#ISCELL
  standard tap *
  page83_i52
#ISCELL
  standard tap *
  page83_i53
#ISCELL
  standard tap *
  page83_i54
#ISCELL
  standard tap *
  page83_i55
#ISCELL
  standard tap *
  page83_i56
#ISCELL
  standard tap *
  page83_i57
#ISCELL
  standard tap *
  page83_i58
#ISCELL
  standard tap *
  page83_i59
#ISCELL
  standard offpage *
  page83_i6
#ISCELL
  standard tap *
  page83_i60
#ISCELL
  standard tap *
  page83_i61
#ISCELL
  standard tap *
  page83_i62
#ISCELL
  standard tap *
  page83_i63
#ISCELL
  standard tap *
  page83_i64
#ISCELL
  standard tap *
  page83_i65
#ISCELL
  standard tap *
  page83_i66
#ISCELL
  standard tap *
  page83_i67
#ISCELL
  standard tap *
  page83_i68
#ISCELL
  standard tap *
  page83_i69
#ISCELL
  standard offpage *
  page83_i7
#ISCELL
  standard tap *
  page83_i70
#ISCELL
  standard tap *
  page83_i71
#ISCELL
  standard tap *
  page83_i72
#ISCELL
  standard tap *
  page83_i73
#ISCELL
  standard tap *
  page83_i74
#ISCELL
  standard tap *
  page83_i75
#ISCELL
  standard tap *
  page83_i76
#ISCELL
  standard tap *
  page83_i77
#ISCELL
  standard tap *
  page83_i78
#ISCELL
  standard tap *
  page83_i79
#ISCELL
  standard offpage *
  page83_i8
#ISCELL
  standard tap *
  page83_i80
#ISCELL
  standard tap *
  page83_i81
#ISCELL
  standard tap *
  page83_i82
#ISCELL
  standard tap *
  page83_i83
#ISCELL
  standard tap *
  page83_i84
#ISCELL
  standard tap *
  page83_i85
#ISCELL
  standard tap *
  page83_i86
#ISCELL
  standard tap *
  page83_i87
#ISCELL
  standard tap *
  page83_i88
#ISCELL
  standard tap *
  page83_i89
#ISCELL
  standard offpage *
  page83_i9
#ISCELL
  standard tap *
  page83_i90
#ISCELL
  standard tap *
  page83_i91
#ISCELL
  standard tap *
  page83_i92
#ISCELL
  standard tap *
  page83_i93
#ISCELL
  standard tap *
  page83_i94
#ISCELL
  standard tap *
  page83_i95
#ISCELL
  standard tap *
  page83_i96
#ISCELL
  standard tap *
  page83_i97
#ISCELL
  standard tap *
  page83_i98
#ISCELL
  standard tap *
  page83_i99
